# BASEBOARD_FAB2 (Tioga Pass) — schematic netlist excerpt (pin names and nets, part order shuffled) for the footprints in the layout excerpt that follows; sources: Cadence DE-HDL packaged netlist, KiCad conversion of Wiwynn_Tioga_Pass_MB.brd

R9P22  RES  0.0 5% CHIP  pkg 0402  page 208 : A = VR_PVCCIN_CPU1_PH3_VCIN ; B = P5V_STBY
C3M26  CAP  0.22UF 16V 10% X7R  pkg 0402  page 105 : A = P3E_CPU0_PE1_PCH_R_RXN<11> ; B = P3E_CPU0_PE1_PCH_RXN<11>
R1T4  RES  2.7K 1% CHIP  pkg 0402  page 164 : A = P3V3_STBY ; B = FM_BOARD_REV_ID0

(kicad_pcb
	(version 20260206)
	(generator "pcbnew")
	(generator_version "10.0")
	(general
		(thickness 1.6)
		(legacy_teardrops no)
	)
	(paper "A4")
	(title_block
		(title "Wiwynn_Tioga_Pass_MB.brd")
		(comment 1 "Tioga Pass / footprints 3806-3808 of 4770")
	)
	(layers
		(0 "F.Cu" signal "TOP")
		(4 "In1.Cu" signal "L2GND")
		(6 "In2.Cu" signal "L3")
		(8 "In3.Cu" signal "L4GND")
		(10 "In4.Cu" signal "L5")
		(12 "In5.Cu" signal "L6GND")
		(14 "In6.Cu" signal "L7VCC")
		(16 "In7.Cu" signal "L8VCC")
		(18 "In8.Cu" signal "L9GND")
		(20 "In9.Cu" signal "L10")
		(22 "In10.Cu" signal "L11GND")
		(24 "In11.Cu" signal "L12")
		(26 "In12.Cu" signal "L13GND")
		(2 "B.Cu" signal "BOTTOM")
		(9 "F.Adhes" user "F.Adhesive")
		(11 "B.Adhes" user "B.Adhesive")
		(13 "F.Paste" user "Package Geometry/Pastemask Top")
		(15 "B.Paste" user "Package Geometry/Pastemask Bottom")
		(5 "F.SilkS" user "Ref Des/Silkscreen Top")
		(7 "B.SilkS" user "Ref Des/Silkscreen Bottom")
		(1 "F.Mask" user "Board Geometry/Soldermask Top")
		(3 "B.Mask" user "Board Geometry/Soldermask Bottom")
		(17 "Dwgs.User" user "User.Drawings")
		(19 "Cmts.User" user "User.Comments")
		(21 "Eco1.User" user "User.Eco1")
		(23 "Eco2.User" user "User.Eco2")
		(25 "Edge.Cuts" user "Board Geometry/Outline")
		(27 "Margin" user)
		(31 "F.CrtYd" user "Package Geometry/Place Bound Top")
		(29 "B.CrtYd" user "Package Geometry/Place Bound Bottom")
		(35 "F.Fab" user "Ref Des/Assembly Top")
		(33 "B.Fab" user "Ref Des/Assembly Bottom")
	)
	(footprint ""
		(layer "B.Cu")
		(at 409.829 -48.768)
		(property "Reference" "R1T4"
			(at 0 0 0)
			(layer "B.SilkS")
			(hide yes)
			(effects
				(font
					(size 1.27 1.27)
				)
				(justify mirror)
			)
		)
		(property "Value" ""
			(at 0 0 0)
			(layer "B.Fab")
			(effects
				(font
					(size 1.27 1.27)
				)
				(justify mirror)
			)
		)
		(duplicate_pad_numbers_are_jumpers no)
		(fp_poly
			(pts
				(xy 0.2794 -0.1016) (xy -0.2794 -0.1016) (xy -0.2794 0.9906) (xy 0.2794 0.9906)
			)
			(stroke
				(width 0)
				(type default)
			)
			(fill no)
			(layer "B.CrtYd")
		)
		(fp_line
			(start -0.2794 -0.1016)
			(end 0.2794 -0.1016)
			(stroke
				(width 0.1)
				(type default)
			)
			(layer "B.Fab")
		)
		(fp_line
			(start -0.2794 0.9906)
			(end -0.2794 -0.1016)
			(stroke
				(width 0.1)
				(type default)
			)
			(layer "B.Fab")
		)
		(fp_line
			(start 0.2794 -0.1016)
			(end 0.2794 0.9906)
			(stroke
				(width 0.1)
				(type default)
			)
			(layer "B.Fab")
		)
		(fp_line
			(start 0.2794 0.9906)
			(end -0.2794 0.9906)
			(stroke
				(width 0.1)
				(type default)
			)
			(layer "B.Fab")
		)
		(pad "1" smd rect
			(at 0 0 180)
			(size 0.508 0.508)
			(layers "B.Cu" "B.Mask" "B.Paste")
			(net "P3V3_STBY")
		)
		(pad "2" smd rect
			(at 0 0.889 180)
			(size 0.508 0.508)
			(layers "B.Cu" "B.Mask" "B.Paste")
			(net "FM_BOARD_REV_ID0")
		)
	)
	(footprint ""
		(layer "B.Cu")
		(at 32.3088 -70.7898 90)
		(property "Reference" "R9P22"
			(at 0 0 90)
			(layer "B.SilkS")
			(hide yes)
			(effects
				(font
					(size 1.27 1.27)
				)
				(justify mirror)
			)
		)
		(property "Value" ""
			(at 0 0 90)
			(layer "B.Fab")
			(effects
				(font
					(size 1.27 1.27)
				)
				(justify mirror)
			)
		)
		(duplicate_pad_numbers_are_jumpers no)
		(fp_poly
			(pts
				(xy 0.2794 -0.1016) (xy -0.2794 -0.1016) (xy -0.2794 0.9906) (xy 0.2794 0.9906)
			)
			(stroke
				(width 0)
				(type default)
			)
			(fill no)
			(layer "B.CrtYd")
		)
		(fp_line
			(start 0.2794 -0.1016)
			(end 0.2794 0.9906)
			(stroke
				(width 0.1)
				(type default)
			)
			(layer "B.Fab")
		)
		(fp_line
			(start -0.2794 -0.1016)
			(end 0.2794 -0.1016)
			(stroke
				(width 0.1)
				(type default)
			)
			(layer "B.Fab")
		)
		(fp_line
			(start 0.2794 0.9906)
			(end -0.2794 0.9906)
			(stroke
				(width 0.1)
				(type default)
			)
			(layer "B.Fab")
		)
		(fp_line
			(start -0.2794 0.9906)
			(end -0.2794 -0.1016)
			(stroke
				(width 0.1)
				(type default)
			)
			(layer "B.Fab")
		)
		(pad "1" smd rect
			(at 0 0 270)
			(size 0.508 0.508)
			(layers "B.Cu" "B.Mask" "B.Paste")
			(net "VR_PVCCIN_CPU1_PH3_VCIN")
		)
		(pad "2" smd rect
			(at 0 0.889 270)
			(size 0.508 0.508)
			(layers "B.Cu" "B.Mask" "B.Paste")
			(net "P5V_STBY")
		)
		(zone
			(layer "B.Cu")
			(hatch none 0.5)
			(connect_pads
				(clearance 0)
			)
			(min_thickness 0.25)
			(keepout
				(tracks allowed)
				(vias not_allowed)
				(pads allowed)
				(copperpour not_allowed)
				(footprints allowed)
			)
			(placement
				(enabled no)
				(sheetname "")
			)
			(fill
				(thermal_gap 0.5)
				(thermal_bridge_width 0.5)
				(island_removal_mode 0)
			)
			(polygon
				(pts
					(xy 32.5628 -71.0438) (xy 32.5628 -70.5358) (xy 32.9438 -70.5358) (xy 32.9438 -71.0438)
				)
			)
		)
		(zone
			(layer "B.Cu")
			(hatch none 0.5)
			(connect_pads
				(clearance 0)
			)
			(min_thickness 0.25)
			(keepout
				(tracks not_allowed)
				(vias allowed)
				(pads allowed)
				(copperpour not_allowed)
				(footprints allowed)
			)
			(placement
				(enabled no)
				(sheetname "")
			)
			(fill
				(thermal_gap 0.5)
				(thermal_bridge_width 0.5)
				(island_removal_mode 0)
			)
			(polygon
				(pts
					(xy 32.9438 -71.0438) (xy 32.9438 -70.5358) (xy 32.5628 -70.5358) (xy 32.5628 -71.0438)
				)
			)
		)
	)
	(footprint ""
		(layer "B.Cu")
		(at 362.715556 -122.510042 -90)
		(property "Reference" "C3M26"
			(at 0 0 90)
			(layer "B.SilkS")
			(hide yes)
			(effects
				(font
					(size 1.27 1.27)
				)
				(justify mirror)
			)
		)
		(property "Value" ""
			(at 0 0 90)
			(layer "B.Fab")
			(effects
				(font
					(size 1.27 1.27)
				)
				(justify mirror)
			)
		)
		(duplicate_pad_numbers_are_jumpers no)
		(fp_poly
			(pts
				(xy -0.3048 -0.1016) (xy -0.3048 0.9906) (xy 0.3048 0.9906) (xy 0.3048 -0.1016)
			)
			(stroke
				(width 0)
				(type default)
			)
			(fill no)
			(layer "B.CrtYd")
		)
		(fp_line
			(start -0.3048 0.9906)
			(end -0.3048 -0.1016)
			(stroke
				(width 0.1)
				(type default)
			)
			(layer "B.Fab")
		)
		(fp_line
			(start 0.3048 0.9906)
			(end -0.3048 0.9906)
			(stroke
				(width 0.1)
				(type default)
			)
			(layer "B.Fab")
		)
		(fp_line
			(start -0.3048 -0.1016)
			(end 0.3048 -0.1016)
			(stroke
				(width 0.1)
				(type default)
			)
			(layer "B.Fab")
		)
		(fp_line
			(start 0.3048 -0.1016)
			(end 0.3048 0.9906)
			(stroke
				(width 0.1)
				(type default)
			)
			(layer "B.Fab")
		)
		(pad "1" smd rect
			(at 0 0 90)
			(size 0.508 0.508)
			(layers "B.Cu" "B.Mask" "B.Paste")
			(net "P3E_CPU0_PE1_PCH_R_RXN<11>")
		)
		(pad "2" smd rect
			(at 0 0.889 90)
			(size 0.508 0.508)
			(layers "B.Cu" "B.Mask" "B.Paste")
			(net "P3E_CPU0_PE1_PCH_RXN<11>")
		)
		(zone
			(layer "B.Cu")
			(hatch none 0.5)
			(connect_pads
				(clearance 0)
			)
			(min_thickness 0.25)
			(keepout
				(tracks not_allowed)
				(vias allowed)
				(pads allowed)
				(copperpour not_allowed)
				(footprints allowed)
			)
			(placement
				(enabled no)
				(sheetname "")
			)
			(fill
				(thermal_gap 0.5)
				(thermal_bridge_width 0.5)
				(island_removal_mode 0)
			)
			(polygon
				(pts
					(xy 362.080556 -122.256042) (xy 362.080556 -122.764042) (xy 362.461556 -122.764042) (xy 362.461556 -122.256042)
				)
			)
		)
		(zone
			(layer "B.Cu")
			(hatch none 0.5)
			(connect_pads
				(clearance 0)
			)
			(min_thickness 0.25)
			(keepout
				(tracks allowed)
				(vias not_allowed)
				(pads allowed)
				(copperpour not_allowed)
				(footprints allowed)
			)
			(placement
				(enabled no)
				(sheetname "")
			)
			(fill
				(thermal_gap 0.5)
				(thermal_bridge_width 0.5)
				(island_removal_mode 0)
			)
			(polygon
				(pts
					(xy 362.461556 -122.256042) (xy 362.461556 -122.764042) (xy 362.080556 -122.764042) (xy 362.080556 -122.256042)
				)
			)
		)
	)
)
